(kicad_pcb
	(version 20241229)
	(generator "pcbnew")
	(generator_version "9.0")
	(general
		(thickness 1.599998)
		(legacy_teardrops no)
	)
	(paper "A4")
	(title_block
		(title "Artix - Datacenter Secure Control Module (DC-SCM)")
		(date "2024-11-06")
		(rev "1.1.3")
		(comment 9 "footprints 154-158 of 544")
	)
	(layers
		(0 "F.Cu" signal)
		(4 "In1.Cu" signal)
		(6 "In2.Cu" signal)
		(8 "In3.Cu" signal)
		(10 "In4.Cu" signal)
		(12 "In5.Cu" signal)
		(14 "In6.Cu" signal)
		(2 "B.Cu" signal)
		(9 "F.Adhes" user "F.Adhesive")
		(11 "B.Adhes" user "B.Adhesive")
		(13 "F.Paste" user)
		(15 "B.Paste" user)
		(5 "F.SilkS" user "F.Silkscreen")
		(7 "B.SilkS" user "B.Silkscreen")
		(1 "F.Mask" user)
		(3 "B.Mask" user)
		(17 "Dwgs.User" user "User.Drawings")
		(19 "Cmts.User" user "User.Comments")
		(21 "Eco1.User" user "User.Eco1")
		(23 "Eco2.User" user "User.Eco2")
		(25 "Edge.Cuts" user)
		(27 "Margin" user)
		(31 "F.CrtYd" user "F.Courtyard")
		(29 "B.CrtYd" user "B.Courtyard")
		(35 "F.Fab" user)
		(33 "B.Fab" user)
	)
	(footprint "antmicro-footprints:LED_0603_1608Metric_G"
		(layer "F.Cu")
		(at 75.719 93.931 180)
		(descr "LED SMD 0603 Green")
		(tags "LED SMD 0603 Green")
		(property "Reference" "D7"
			(at -2.781 -0.469 0)
			(layer "F.SilkS")
			(effects
				(font
					(size 0.7 0.7)
					(thickness 0.15)
				)
				(justify right bottom)
			)
		)
		(property "Value" "LED_G_0603_LG_L29K-G2J1-24-Z"
			(at 0 1.6 0)
			(layer "F.Fab")
			(effects
				(font
					(size 0.7 0.7)
					(thickness 0.15)
				)
				(justify right bottom)
			)
		)
		(property "Datasheet" "https://look.ams-osram.com/m/19ee86b3ae0ee95b/original/LG-L29K.pdf"
			(at 0 0 180)
			(layer "F.Fab")
			(hide yes)
			(effects
				(font
					(size 1.27 1.27)
					(thickness 0.15)
				)
			)
		)
		(property "Description" "LED, Green, SMD, 0603, 20 mA, 1.7 V, 570 nm"
			(at 0 0 180)
			(layer "F.Fab")
			(hide yes)
			(effects
				(font
					(size 1.27 1.27)
					(thickness 0.15)
				)
			)
		)
		(property "Author" "Antmicro"
			(at 151.438 187.862 0)
			(layer "F.Fab")
			(hide yes)
			(effects
				(font
					(size 1 1)
					(thickness 0.15)
				)
			)
		)
		(property "Color" "Green"
			(at 151.438 187.862 0)
			(layer "F.Fab")
			(hide yes)
			(effects
				(font
					(size 1 1)
					(thickness 0.15)
				)
			)
		)
		(property "License" "Apache-2.0"
			(at 151.438 187.862 0)
			(layer "F.Fab")
			(hide yes)
			(effects
				(font
					(size 1 1)
					(thickness 0.15)
				)
			)
		)
		(property "MPN" "LG L29K-G2J1-24-Z"
			(at 151.438 187.862 0)
			(layer "F.Fab")
			(hide yes)
			(effects
				(font
					(size 1 1)
					(thickness 0.15)
				)
			)
		)
		(property "Manufacturer" "OSRAM"
			(at 151.438 187.862 0)
			(layer "F.Fab")
			(hide yes)
			(effects
				(font
					(size 1 1)
					(thickness 0.15)
				)
			)
		)
		(sheetname "/Power supply/")
		(sheetfile "power-supply.kicad_sch")
		(attr smd)
		(fp_line
			(start 0.22 0.35)
			(end -0.22 0.35)
			(stroke
				(width 0.15)
				(type solid)
			)
			(layer "F.SilkS")
		)
		(fp_line
			(start 0.22 -0.35)
			(end -0.22 -0.35)
			(stroke
				(width 0.15)
				(type solid)
			)
			(layer "F.SilkS")
		)
		(fp_line
			(start 0.105328 0.201008)
			(end 0.105328 -0.198992)
			(stroke
				(width 0.1)
				(type solid)
			)
			(layer "F.SilkS")
		)
		(fp_line
			(start 0.105328 0.201008)
			(end -0.094672 0.001008)
			(stroke
				(width 0.1)
				(type solid)
			)
			(layer "F.SilkS")
		)
		(fp_line
			(start 0.105328 0.001008)
			(end 0.24 0.001)
			(stroke
				(width 0.1)
				(type solid)
			)
			(layer "F.SilkS")
		)
		(fp_line
			(start -0.094672 0.201008)
			(end -0.094672 -0.198992)
			(stroke
				(width 0.1)
				(type solid)
			)
			(layer "F.SilkS")
		)
		(fp_line
			(start -0.094672 0.001008)
			(end 0.105328 -0.198992)
			(stroke
				(width 0.1)
				(type solid)
			)
			(layer "F.SilkS")
		)
		(fp_line
			(start -0.094672 0.001008)
			(end -0.24 0.001008)
			(stroke
				(width 0.1)
				(type solid)
			)
			(layer "F.SilkS")
		)
		(fp_line
			(start -1.18 -0.319)
			(end -1.18 0.321)
			(stroke
				(width 0.15)
				(type solid)
			)
			(layer "F.SilkS")
		)
		(fp_rect
			(start 1.25 0.65)
			(end -1.25 -0.65)
			(stroke
				(width 0.05)
				(type solid)
			)
			(fill no)
			(layer "F.CrtYd")
		)
		(fp_line
			(start 0.599 0)
			(end 0.201 0)
			(stroke
				(width 0.15)
				(type solid)
			)
			(layer "F.Fab")
		)
		(fp_line
			(start 0.201 0.2)
			(end 0.201 0)
			(stroke
				(width 0.15)
				(type solid)
			)
			(layer "F.Fab")
		)
		(fp_line
			(start 0.201 0)
			(end 0.201 -0.202)
			(stroke
				(width 0.15)
				(type solid)
			)
			(layer "F.Fab")
		)
		(fp_line
			(start 0.201 -0.202)
			(end -0.101 0)
			(stroke
				(width 0.15)
				(type solid)
			)
			(layer "F.Fab")
		)
		(fp_line
			(start -0.101 0)
			(end 0.201 0.2)
			(stroke
				(width 0.15)
				(type solid)
			)
			(layer "F.Fab")
		)
		(fp_line
			(start -0.199 0.2)
			(end -0.199 0.1)
			(stroke
				(width 0.15)
				(type solid)
			)
			(layer "F.Fab")
		)
		(fp_line
			(start -0.199 0)
			(end -0.597 0)
			(stroke
				(width 0.15)
				(type solid)
			)
			(layer "F.Fab")
		)
		(fp_line
			(start -0.199 -0.202)
			(end -0.199 0.1)
			(stroke
				(width 0.15)
				(type solid)
			)
			(layer "F.Fab")
		)
		(fp_rect
			(start 0.848 0.4)
			(end -0.85 -0.402)
			(stroke
				(width 0.15)
				(type solid)
			)
			(fill no)
			(layer "F.Fab")
		)
		(pad "1" smd roundrect
			(at -0.7 0)
			(size 0.8 1)
			(layers "F.Cu" "F.Mask" "F.Paste")
			(roundrect_rratio 0.2)
			(net 218 "Net-(D7-C)")
			(pinfunction "C")
			(pintype "passive")
		)
		(pad "2" smd roundrect
			(at 0.7 0)
			(size 0.8 1)
			(layers "F.Cu" "F.Mask" "F.Paste")
			(roundrect_rratio 0.2)
			(net 219 "Net-(D7-A)")
			(pinfunction "A")
			(pintype "passive")
		)
	)
	(footprint "antmicro-footprints:LED_0603_1608Metric_G"
		(layer "F.Cu")
		(at 75.719 97.995 180)
		(descr "LED SMD 0603 Green")
		(tags "LED SMD 0603 Green")
		(property "Reference" "D8"
			(at -2.781 -0.405 0)
			(layer "F.SilkS")
			(effects
				(font
					(size 0.7 0.7)
					(thickness 0.15)
				)
				(justify right bottom)
			)
		)
		(property "Value" "LED_G_0603_LG_L29K-G2J1-24-Z"
			(at 0 1.6 0)
			(layer "F.Fab")
			(effects
				(font
					(size 0.7 0.7)
					(thickness 0.15)
				)
				(justify right bottom)
			)
		)
		(property "Datasheet" "https://look.ams-osram.com/m/19ee86b3ae0ee95b/original/LG-L29K.pdf"
			(at 0 0 180)
			(layer "F.Fab")
			(hide yes)
			(effects
				(font
					(size 1.27 1.27)
					(thickness 0.15)
				)
			)
		)
		(property "Description" "LED, Green, SMD, 0603, 20 mA, 1.7 V, 570 nm"
			(at 0 0 180)
			(layer "F.Fab")
			(hide yes)
			(effects
				(font
					(size 1.27 1.27)
					(thickness 0.15)
				)
			)
		)
		(property "Author" "Antmicro"
			(at 151.438 195.99 0)
			(layer "F.Fab")
			(hide yes)
			(effects
				(font
					(size 1 1)
					(thickness 0.15)
				)
			)
		)
		(property "Color" "Green"
			(at 151.438 195.99 0)
			(layer "F.Fab")
			(hide yes)
			(effects
				(font
					(size 1 1)
					(thickness 0.15)
				)
			)
		)
		(property "License" "Apache-2.0"
			(at 151.438 195.99 0)
			(layer "F.Fab")
			(hide yes)
			(effects
				(font
					(size 1 1)
					(thickness 0.15)
				)
			)
		)
		(property "MPN" "LG L29K-G2J1-24-Z"
			(at 151.438 195.99 0)
			(layer "F.Fab")
			(hide yes)
			(effects
				(font
					(size 1 1)
					(thickness 0.15)
				)
			)
		)
		(property "Manufacturer" "OSRAM"
			(at 151.438 195.99 0)
			(layer "F.Fab")
			(hide yes)
			(effects
				(font
					(size 1 1)
					(thickness 0.15)
				)
			)
		)
		(sheetname "/Power supply/")
		(sheetfile "power-supply.kicad_sch")
		(attr smd)
		(fp_line
			(start 0.22 0.35)
			(end -0.22 0.35)
			(stroke
				(width 0.15)
				(type solid)
			)
			(layer "F.SilkS")
		)
		(fp_line
			(start 0.22 -0.35)
			(end -0.22 -0.35)
			(stroke
				(width 0.15)
				(type solid)
			)
			(layer "F.SilkS")
		)
		(fp_line
			(start 0.105328 0.201008)
			(end 0.105328 -0.198992)
			(stroke
				(width 0.1)
				(type solid)
			)
			(layer "F.SilkS")
		)
		(fp_line
			(start 0.105328 0.201008)
			(end -0.094672 0.001008)
			(stroke
				(width 0.1)
				(type solid)
			)
			(layer "F.SilkS")
		)
		(fp_line
			(start 0.105328 0.001008)
			(end 0.24 0.001)
			(stroke
				(width 0.1)
				(type solid)
			)
			(layer "F.SilkS")
		)
		(fp_line
			(start -0.094672 0.201008)
			(end -0.094672 -0.198992)
			(stroke
				(width 0.1)
				(type solid)
			)
			(layer "F.SilkS")
		)
		(fp_line
			(start -0.094672 0.001008)
			(end 0.105328 -0.198992)
			(stroke
				(width 0.1)
				(type solid)
			)
			(layer "F.SilkS")
		)
		(fp_line
			(start -0.094672 0.001008)
			(end -0.24 0.001008)
			(stroke
				(width 0.1)
				(type solid)
			)
			(layer "F.SilkS")
		)
		(fp_line
			(start -1.18 -0.319)
			(end -1.18 0.321)
			(stroke
				(width 0.15)
				(type solid)
			)
			(layer "F.SilkS")
		)
		(fp_rect
			(start 1.25 0.65)
			(end -1.25 -0.65)
			(stroke
				(width 0.05)
				(type solid)
			)
			(fill no)
			(layer "F.CrtYd")
		)
		(fp_line
			(start 0.599 0)
			(end 0.201 0)
			(stroke
				(width 0.15)
				(type solid)
			)
			(layer "F.Fab")
		)
		(fp_line
			(start 0.201 0.2)
			(end 0.201 0)
			(stroke
				(width 0.15)
				(type solid)
			)
			(layer "F.Fab")
		)
		(fp_line
			(start 0.201 0)
			(end 0.201 -0.202)
			(stroke
				(width 0.15)
				(type solid)
			)
			(layer "F.Fab")
		)
		(fp_line
			(start 0.201 -0.202)
			(end -0.101 0)
			(stroke
				(width 0.15)
				(type solid)
			)
			(layer "F.Fab")
		)
		(fp_line
			(start -0.101 0)
			(end 0.201 0.2)
			(stroke
				(width 0.15)
				(type solid)
			)
			(layer "F.Fab")
		)
		(fp_line
			(start -0.199 0.2)
			(end -0.199 0.1)
			(stroke
				(width 0.15)
				(type solid)
			)
			(layer "F.Fab")
		)
		(fp_line
			(start -0.199 0)
			(end -0.597 0)
			(stroke
				(width 0.15)
				(type solid)
			)
			(layer "F.Fab")
		)
		(fp_line
			(start -0.199 -0.202)
			(end -0.199 0.1)
			(stroke
				(width 0.15)
				(type solid)
			)
			(layer "F.Fab")
		)
		(fp_rect
			(start 0.848 0.4)
			(end -0.85 -0.402)
			(stroke
				(width 0.15)
				(type solid)
			)
			(fill no)
			(layer "F.Fab")
		)
		(pad "1" smd roundrect
			(at -0.7 0)
			(size 0.8 1)
			(layers "F.Cu" "F.Mask" "F.Paste")
			(roundrect_rratio 0.2)
			(net 223 "Net-(D8-C)")
			(pinfunction "C")
			(pintype "passive")
		)
		(pad "2" smd roundrect
			(at 0.7 0)
			(size 0.8 1)
			(layers "F.Cu" "F.Mask" "F.Paste")
			(roundrect_rratio 0.2)
			(net 224 "Net-(D8-A)")
			(pinfunction "A")
			(pintype "passive")
		)
	)
	(footprint "antmicro-footprints:R_0402_1005Metric"
		(layer "F.Cu")
		(at 73.15 89.9 180)
		(descr "Resistor SMD 0402")
		(tags "resistor SMD 0402")
		(property "Reference" "R95"
			(at -1.05 0.495 0)
			(layer "F.SilkS")
			(effects
				(font
					(size 0.7 0.7)
					(thickness 0.15)
				)
				(justify right bottom)
			)
		)
		(property "Value" "R_1k_0402"
			(at 0 1.4 0)
			(layer "F.Fab")
			(effects
				(font
					(size 0.7 0.7)
					(thickness 0.15)
				)
				(justify right bottom)
			)
		)
		(property "Datasheet" "https://www.bourns.com/docs/product-datasheets/cr.pdf"
			(at 0 0 180)
			(layer "F.Fab")
			(hide yes)
			(effects
				(font
					(size 1.27 1.27)
					(thickness 0.15)
				)
			)
		)
		(property "Description" "SMD Chip Resistor, 1 kohm, ± 1%, 63 mW, 0402 [1005 Metric], Thick Film, General Purpose"
			(at 0 0 180)
			(layer "F.Fab")
			(hide yes)
			(effects
				(font
					(size 1.27 1.27)
					(thickness 0.15)
				)
			)
		)
		(property "Author" "Antmicro"
			(at 146.3 179.8 0)
			(layer "F.Fab")
			(hide yes)
			(effects
				(font
					(size 1 1)
					(thickness 0.15)
				)
			)
		)
		(property "License" "Apache-2.0"
			(at 146.3 179.8 0)
			(layer "F.Fab")
			(hide yes)
			(effects
				(font
					(size 1 1)
					(thickness 0.15)
				)
			)
		)
		(property "MPN" "CR0402-FX-1001GLF"
			(at 146.3 179.8 0)
			(layer "F.Fab")
			(hide yes)
			(effects
				(font
					(size 1 1)
					(thickness 0.15)
				)
			)
		)
		(property "Manufacturer" "Bourns"
			(at 146.3 179.8 0)
			(layer "F.Fab")
			(hide yes)
			(effects
				(font
					(size 1 1)
					(thickness 0.15)
				)
			)
		)
		(property "Tolerance" "1%"
			(at 146.3 179.8 0)
			(layer "F.Fab")
			(hide yes)
			(effects
				(font
					(size 1 1)
					(thickness 0.15)
				)
			)
		)
		(property "Val" "1k"
			(at 146.3 179.8 0)
			(layer "F.Fab")
			(hide yes)
			(effects
				(font
					(size 1 1)
					(thickness 0.15)
				)
			)
		)
		(sheetname "/Power supply/")
		(sheetfile "power-supply.kicad_sch")
		(attr smd)
		(fp_rect
			(start -0.925 -0.47)
			(end 0.925 0.47)
			(stroke
				(width 0.05)
				(type default)
			)
			(fill no)
			(layer "F.CrtYd")
		)
		(fp_rect
			(start -0.5 -0.25)
			(end 0.5 0.25)
			(stroke
				(width 0.15)
				(type solid)
			)
			(fill no)
			(layer "F.Fab")
		)
		(pad "1" smd roundrect
			(at -0.48 0 180)
			(size 0.59 0.64)
			(layers "F.Cu" "F.Mask" "F.Paste")
			(roundrect_rratio 0.25)
			(net 215 "Net-(D5-A)")
			(pintype "passive")
		)
		(pad "2" smd roundrect
			(at 0.48 0 180)
			(size 0.59 0.64)
			(layers "F.Cu" "F.Mask" "F.Paste")
			(roundrect_rratio 0.25)
			(net 2 "VCC3V3")
			(pintype "passive")
		)
	)
	(footprint "antmicro-footprints:R_0402_1005Metric"
		(layer "F.Cu")
		(at 84.19 123.645 -90)
		(descr "Resistor SMD 0402")
		(tags "resistor SMD 0402")
		(property "Reference" "R147"
			(at 0.855 -0.31 90)
			(layer "F.SilkS")
			(effects
				(font
					(size 0.7 0.7)
					(thickness 0.15)
				)
				(justify right bottom)
			)
		)
		(property "Value" "R_0R_0402"
			(at 0 1.4 90)
			(layer "F.Fab")
			(effects
				(font
					(size 0.7 0.7)
					(thickness 0.15)
				)
				(justify right bottom)
			)
		)
		(property "Datasheet" "https://industrial.panasonic.com/cdbs/www-data/pdf/RDA0000/AOA0000C301.pdf"
			(at 0 0 270)
			(layer "F.Fab")
			(hide yes)
			(effects
				(font
					(size 1.27 1.27)
					(thickness 0.15)
				)
			)
		)
		(property "Description" "SMD Chip Resistor, Jumper, 0 ohm, 100 mW, 0402 [1005 Metric], Thick Film, General Purpose"
			(at 0 0 270)
			(layer "F.Fab")
			(hide yes)
			(effects
				(font
					(size 1.27 1.27)
					(thickness 0.15)
				)
			)
		)
		(property "Author" "Antmicro"
			(at -39.455 207.835 0)
			(layer "F.Fab")
			(hide yes)
			(effects
				(font
					(size 1 1)
					(thickness 0.15)
				)
			)
		)
		(property "Current" "1A"
			(at -39.455 207.835 0)
			(layer "F.Fab")
			(hide yes)
			(effects
				(font
					(size 1 1)
					(thickness 0.15)
				)
			)
		)
		(property "License" "Apache-2.0"
			(at -39.455 207.835 0)
			(layer "F.Fab")
			(hide yes)
			(effects
				(font
					(size 1 1)
					(thickness 0.15)
				)
			)
		)
		(property "MPN" "ERJ2GE0R00X"
			(at -39.455 207.835 0)
			(layer "F.Fab")
			(hide yes)
			(effects
				(font
					(size 1 1)
					(thickness 0.15)
				)
			)
		)
		(property "Manufacturer" "Panasonic"
			(at -39.455 207.835 0)
			(layer "F.Fab")
			(hide yes)
			(effects
				(font
					(size 1 1)
					(thickness 0.15)
				)
			)
		)
		(property "Tolerance" "~"
			(at -39.455 207.835 0)
			(layer "F.Fab")
			(hide yes)
			(effects
				(font
					(size 1 1)
					(thickness 0.15)
				)
			)
		)
		(property "Val" "0R"
			(at -39.455 207.835 0)
			(layer "F.Fab")
			(hide yes)
			(effects
				(font
					(size 1 1)
					(thickness 0.15)
				)
			)
		)
		(sheetname "/Edge connector/")
		(sheetfile "edge-connector.kicad_sch")
		(attr smd)
		(fp_rect
			(start -0.925 -0.47)
			(end 0.925 0.47)
			(stroke
				(width 0.05)
				(type default)
			)
			(fill no)
			(layer "F.CrtYd")
		)
		(fp_rect
			(start -0.5 -0.25)
			(end 0.5 0.25)
			(stroke
				(width 0.15)
				(type solid)
			)
			(fill no)
			(layer "F.Fab")
		)
		(pad "1" smd roundrect
			(at -0.48 0 270)
			(size 0.59 0.64)
			(layers "F.Cu" "F.Mask" "F.Paste")
			(roundrect_rratio 0.25)
			(net 526 "SPI0_MISO_R")
			(pintype "passive")
		)
		(pad "2" smd roundrect
			(at 0.48 0 270)
			(size 0.59 0.64)
			(layers "F.Cu" "F.Mask" "F.Paste")
			(roundrect_rratio 0.25)
			(net 58 "SPI0_MISO")
			(pintype "passive")
		)
	)
	(footprint "antmicro-footprints:R_0402_1005Metric"
		(layer "F.Cu")
		(at 82.19 123.645 -90)
		(descr "Resistor SMD 0402")
		(tags "resistor SMD 0402")
		(property "Reference" "R146"
			(at 0.855 -0.31 90)
			(layer "F.SilkS")
			(effects
				(font
					(size 0.7 0.7)
					(thickness 0.15)
				)
				(justify right bottom)
			)
		)
		(property "Value" "R_0R_0402"
			(at 0 1.4 90)
			(layer "F.Fab")
			(effects
				(font
					(size 0.7 0.7)
					(thickness 0.15)
				)
				(justify right bottom)
			)
		)
		(property "Datasheet" "https://industrial.panasonic.com/cdbs/www-data/pdf/RDA0000/AOA0000C301.pdf"
			(at 0 0 270)
			(layer "F.Fab")
			(hide yes)
			(effects
				(font
					(size 1.27 1.27)
					(thickness 0.15)
				)
			)
		)
		(property "Description" "SMD Chip Resistor, Jumper, 0 ohm, 100 mW, 0402 [1005 Metric], Thick Film, General Purpose"
			(at 0 0 270)
			(layer "F.Fab")
			(hide yes)
			(effects
				(font
					(size 1.27 1.27)
					(thickness 0.15)
				)
			)
		)
		(property "Author" "Antmicro"
			(at -41.455 205.835 0)
			(layer "F.Fab")
			(hide yes)
			(effects
				(font
					(size 1 1)
					(thickness 0.15)
				)
			)
		)
		(property "Current" "1A"
			(at -41.455 205.835 0)
			(layer "F.Fab")
			(hide yes)
			(effects
				(font
					(size 1 1)
					(thickness 0.15)
				)
			)
		)
		(property "License" "Apache-2.0"
			(at -41.455 205.835 0)
			(layer "F.Fab")
			(hide yes)
			(effects
				(font
					(size 1 1)
					(thickness 0.15)
				)
			)
		)
		(property "MPN" "ERJ2GE0R00X"
			(at -41.455 205.835 0)
			(layer "F.Fab")
			(hide yes)
			(effects
				(font
					(size 1 1)
					(thickness 0.15)
				)
			)
		)
		(property "Manufacturer" "Panasonic"
			(at -41.455 205.835 0)
			(layer "F.Fab")
			(hide yes)
			(effects
				(font
					(size 1 1)
					(thickness 0.15)
				)
			)
		)
		(property "Tolerance" "~"
			(at -41.455 205.835 0)
			(layer "F.Fab")
			(hide yes)
			(effects
				(font
					(size 1 1)
					(thickness 0.15)
				)
			)
		)
		(property "Val" "0R"
			(at -41.455 205.835 0)
			(layer "F.Fab")
			(hide yes)
			(effects
				(font
					(size 1 1)
					(thickness 0.15)
				)
			)
		)
		(sheetname "/Edge connector/")
		(sheetfile "edge-connector.kicad_sch")
		(attr smd)
		(fp_rect
			(start -0.925 -0.47)
			(end 0.925 0.47)
			(stroke
				(width 0.05)
				(type default)
			)
			(fill no)
			(layer "F.CrtYd")
		)
		(fp_rect
			(start -0.5 -0.25)
			(end 0.5 0.25)
			(stroke
				(width 0.15)
				(type solid)
			)
			(fill no)
			(layer "F.Fab")
		)
		(pad "1" smd roundrect
			(at -0.48 0 270)
			(size 0.59 0.64)
			(layers "F.Cu" "F.Mask" "F.Paste")
			(roundrect_rratio 0.25)
			(net 525 "SPI0_CS_N_R")
			(pintype "passive")
		)
		(pad "2" smd roundrect
			(at 0.48 0 270)
			(size 0.59 0.64)
			(layers "F.Cu" "F.Mask" "F.Paste")
			(roundrect_rratio 0.25)
			(net 55 "SPI0_CS_N")
			(pintype "passive")
		)
	)
)
